# BASEBOARD_FAB2 (Tioga Pass) — schematic netlist excerpt (pin names and nets, part order shuffled) for the footprints in the layout excerpt that follows; sources: Cadence DE-HDL packaged netlist, KiCad conversion of Wiwynn_Tioga_Pass_MB.brd

C5D26  CAP_A  22.0UF 4V 20% X6S  pkg 0603V  page 42 : A = PVCCIN_CPU0 ; B = GND
R1C13  RES  100.0K 1% CHIP  pkg 0402  page 206 : A = VR_FET_SW_P12V_STBY_PVCCIN_CPU1 ; B = VR_PVCCIN_CPU1_AVINSEN
C2D32  CAP_A  22.0UF 4V 20% X6S  pkg 0603V  page 76 : A = PVCCIN_CPU1 ; B = GND

(kicad_pcb
	(version 20260206)
	(generator "pcbnew")
	(generator_version "10.0")
	(general
		(thickness 1.6)
		(legacy_teardrops no)
	)
	(paper "A4")
	(title_block
		(title "Wiwynn_Tioga_Pass_MB.brd")
		(comment 1 "Tioga Pass / footprints 305-307 of 4770")
	)
	(layers
		(0 "F.Cu" signal "TOP")
		(4 "In1.Cu" signal "L2GND")
		(6 "In2.Cu" signal "L3")
		(8 "In3.Cu" signal "L4GND")
		(10 "In4.Cu" signal "L5")
		(12 "In5.Cu" signal "L6GND")
		(14 "In6.Cu" signal "L7VCC")
		(16 "In7.Cu" signal "L8VCC")
		(18 "In8.Cu" signal "L9GND")
		(20 "In9.Cu" signal "L10")
		(22 "In10.Cu" signal "L11GND")
		(24 "In11.Cu" signal "L12")
		(26 "In12.Cu" signal "L13GND")
		(2 "B.Cu" signal "BOTTOM")
		(9 "F.Adhes" user "F.Adhesive")
		(11 "B.Adhes" user "B.Adhesive")
		(13 "F.Paste" user "Package Geometry/Pastemask Top")
		(15 "B.Paste" user "Package Geometry/Pastemask Bottom")
		(5 "F.SilkS" user "Ref Des/Silkscreen Top")
		(7 "B.SilkS" user "Ref Des/Silkscreen Bottom")
		(1 "F.Mask" user "Board Geometry/Soldermask Top")
		(3 "B.Mask" user "Board Geometry/Soldermask Bottom")
		(17 "Dwgs.User" user "User.Drawings")
		(19 "Cmts.User" user "User.Comments")
		(21 "Eco1.User" user "User.Eco1")
		(23 "Eco2.User" user "User.Eco2")
		(25 "Edge.Cuts" user "Board Geometry/Outline")
		(27 "Margin" user)
		(31 "F.CrtYd" user "Package Geometry/Place Bound Top")
		(29 "B.CrtYd" user "Package Geometry/Place Bound Bottom")
		(35 "F.Fab" user "Ref Des/Assembly Top")
		(33 "B.Fab" user "Ref Des/Assembly Bottom")
	)
	(footprint ""
		(layer "F.Cu")
		(at 260.697472 -77.636116)
		(property "Reference" "C5D26"
			(at 0 0 0)
			(layer "F.SilkS")
			(hide yes)
			(effects
				(font
					(size 1.27 1.27)
				)
			)
		)
		(property "Value" ""
			(at 0 0 0)
			(layer "F.Fab")
			(effects
				(font
					(size 1.27 1.27)
				)
			)
		)
		(duplicate_pad_numbers_are_jumpers no)
		(fp_poly
			(pts
				(xy -0.4953 -0.2032) (xy 0.4953 -0.2032) (xy 0.4953 1.6002) (xy -0.4953 1.6002)
			)
			(stroke
				(width 0)
				(type default)
			)
			(fill no)
			(layer "F.CrtYd")
		)
		(fp_line
			(start -0.4953 -0.2032)
			(end 0.4953 -0.2032)
			(stroke
				(width 0.1)
				(type default)
			)
			(layer "F.Fab")
		)
		(fp_line
			(start -0.4953 1.6002)
			(end -0.4953 -0.2032)
			(stroke
				(width 0.1)
				(type default)
			)
			(layer "F.Fab")
		)
		(fp_line
			(start 0.4953 -0.2032)
			(end 0.4953 1.6002)
			(stroke
				(width 0.1)
				(type default)
			)
			(layer "F.Fab")
		)
		(fp_line
			(start 0.4953 1.6002)
			(end -0.4953 1.6002)
			(stroke
				(width 0.1)
				(type default)
			)
			(layer "F.Fab")
		)
		(pad "1" smd rect
			(at 0 0)
			(size 0.762 0.889)
			(layers "F.Cu" "F.Mask" "F.Paste")
			(net "PVCCIN_CPU0")
		)
		(pad "2" smd rect
			(at 0 1.397)
			(size 0.762 0.889)
			(layers "F.Cu" "F.Mask" "F.Paste")
			(net "GND")
		)
		(zone
			(layer "F.Cu")
			(hatch none 0.5)
			(connect_pads
				(clearance 0)
			)
			(min_thickness 0.25)
			(keepout
				(tracks not_allowed)
				(vias allowed)
				(pads allowed)
				(copperpour not_allowed)
				(footprints allowed)
			)
			(placement
				(enabled no)
				(sheetname "")
			)
			(fill
				(thermal_gap 0.5)
				(thermal_bridge_width 0.5)
				(island_removal_mode 0)
			)
			(polygon
				(pts
					(xy 260.316472 -77.191616) (xy 261.078472 -77.191616) (xy 261.078472 -76.683616) (xy 260.316472 -76.683616)
				)
			)
		)
	)
	(footprint ""
		(layer "F.Cu")
		(at 18.288 -100.33)
		(property "Reference" "R1C13"
			(at 0 0 0)
			(layer "F.SilkS")
			(hide yes)
			(effects
				(font
					(size 1.27 1.27)
				)
			)
		)
		(property "Value" ""
			(at 0 0 0)
			(layer "F.Fab")
			(effects
				(font
					(size 1.27 1.27)
				)
			)
		)
		(duplicate_pad_numbers_are_jumpers no)
		(fp_rect
			(start -0.2794 -0.1016)
			(end 0.2794 0.9906)
			(stroke
				(width 0)
				(type default)
			)
			(fill no)
			(layer "F.CrtYd")
		)
		(fp_line
			(start -0.2794 -0.1016)
			(end -0.2794 0.9906)
			(stroke
				(width 0.1)
				(type default)
			)
			(layer "F.Fab")
		)
		(fp_line
			(start -0.2794 0.9906)
			(end 0.2794 0.9906)
			(stroke
				(width 0.1)
				(type default)
			)
			(layer "F.Fab")
		)
		(fp_line
			(start 0.2794 -0.1016)
			(end -0.2794 -0.1016)
			(stroke
				(width 0.1)
				(type default)
			)
			(layer "F.Fab")
		)
		(fp_line
			(start 0.2794 0.9906)
			(end 0.2794 -0.1016)
			(stroke
				(width 0.1)
				(type default)
			)
			(layer "F.Fab")
		)
		(pad "1" smd rect
			(at 0 0)
			(size 0.508 0.508)
			(layers "F.Cu" "F.Mask" "F.Paste")
			(net "VR_FET_SW_P12V_STBY_PVCCIN_CPU1")
		)
		(pad "2" smd rect
			(at 0 0.889)
			(size 0.508 0.508)
			(layers "F.Cu" "F.Mask" "F.Paste")
			(net "VR_PVCCIN_CPU1_AVINSEN")
		)
		(zone
			(layer "F.Cu")
			(hatch none 0.5)
			(connect_pads
				(clearance 0)
			)
			(min_thickness 0.25)
			(keepout
				(tracks not_allowed)
				(vias allowed)
				(pads allowed)
				(copperpour not_allowed)
				(footprints allowed)
			)
			(placement
				(enabled no)
				(sheetname "")
			)
			(fill
				(thermal_gap 0.5)
				(thermal_bridge_width 0.5)
				(island_removal_mode 0)
			)
			(polygon
				(pts
					(xy 18.034 -100.076) (xy 18.034 -99.695) (xy 18.542 -99.695) (xy 18.542 -100.076)
				)
			)
		)
		(zone
			(layer "F.Cu")
			(hatch none 0.5)
			(connect_pads
				(clearance 0)
			)
			(min_thickness 0.25)
			(keepout
				(tracks allowed)
				(vias not_allowed)
				(pads allowed)
				(copperpour not_allowed)
				(footprints allowed)
			)
			(placement
				(enabled no)
				(sheetname "")
			)
			(fill
				(thermal_gap 0.5)
				(thermal_bridge_width 0.5)
				(island_removal_mode 0)
			)
			(polygon
				(pts
					(xy 18.034 -100.076) (xy 18.034 -99.695) (xy 18.542 -99.695) (xy 18.542 -100.076)
				)
			)
		)
	)
	(footprint ""
		(layer "F.Cu")
		(at 95.69704 -73.318116)
		(property "Reference" "C2D32"
			(at 0 0 0)
			(layer "F.SilkS")
			(hide yes)
			(effects
				(font
					(size 1.27 1.27)
				)
			)
		)
		(property "Value" ""
			(at 0 0 0)
			(layer "F.Fab")
			(effects
				(font
					(size 1.27 1.27)
				)
			)
		)
		(duplicate_pad_numbers_are_jumpers no)
		(fp_poly
			(pts
				(xy -0.4953 -0.2032) (xy 0.4953 -0.2032) (xy 0.4953 1.6002) (xy -0.4953 1.6002)
			)
			(stroke
				(width 0)
				(type default)
			)
			(fill no)
			(layer "F.CrtYd")
		)
		(fp_line
			(start -0.4953 -0.2032)
			(end 0.4953 -0.2032)
			(stroke
				(width 0.1)
				(type default)
			)
			(layer "F.Fab")
		)
		(fp_line
			(start -0.4953 1.6002)
			(end -0.4953 -0.2032)
			(stroke
				(width 0.1)
				(type default)
			)
			(layer "F.Fab")
		)
		(fp_line
			(start 0.4953 -0.2032)
			(end 0.4953 1.6002)
			(stroke
				(width 0.1)
				(type default)
			)
			(layer "F.Fab")
		)
		(fp_line
			(start 0.4953 1.6002)
			(end -0.4953 1.6002)
			(stroke
				(width 0.1)
				(type default)
			)
			(layer "F.Fab")
		)
		(pad "1" smd rect
			(at 0 0)
			(size 0.762 0.889)
			(layers "F.Cu" "F.Mask" "F.Paste")
			(net "PVCCIN_CPU1")
		)
		(pad "2" smd rect
			(at 0 1.397)
			(size 0.762 0.889)
			(layers "F.Cu" "F.Mask" "F.Paste")
			(net "GND")
		)
		(zone
			(layer "F.Cu")
			(hatch none 0.5)
			(connect_pads
				(clearance 0)
			)
			(min_thickness 0.25)
			(keepout
				(tracks not_allowed)
				(vias allowed)
				(pads allowed)
				(copperpour not_allowed)
				(footprints allowed)
			)
			(placement
				(enabled no)
				(sheetname "")
			)
			(fill
				(thermal_gap 0.5)
				(thermal_bridge_width 0.5)
				(island_removal_mode 0)
			)
			(polygon
				(pts
					(xy 95.31604 -72.873616) (xy 96.07804 -72.873616) (xy 96.07804 -72.365616) (xy 95.31604 -72.365616)
				)
			)
		)
	)
)
